(kicad_pcb
	(version 20260206)
	(generator "pcbnew")
	(generator_version "10.0")
	(general
		(thickness 1.6)
		(legacy_teardrops no)
	)
	(paper "A4")
	(title_block
		(title "m-2 — Lightning_M.2_BRD.brd")
		(comment 1 "Lightning (Wiwynn / Facebook NVMe JBOF) / footprints 46-53 of 157")
	)
	(layers
		(0 "F.Cu" signal "TOP")
		(4 "In1.Cu" signal "L2GND")
		(6 "In2.Cu" signal "L3")
		(8 "In3.Cu" signal "L4GND")
		(10 "In4.Cu" signal "L5GND")
		(12 "In5.Cu" signal "L6")
		(14 "In6.Cu" signal "L7GND")
		(2 "B.Cu" signal "BOTTOM")
		(9 "F.Adhes" user "F.Adhesive")
		(11 "B.Adhes" user "B.Adhesive")
		(13 "F.Paste" user "Package Geometry/Pastemask Top")
		(15 "B.Paste" user "Package Geometry/Pastemask Bottom")
		(5 "F.SilkS" user "Ref Des/Silkscreen Top")
		(7 "B.SilkS" user "Ref Des/Silkscreen Bottom")
		(1 "F.Mask" user "Board Geometry/Soldermask Top")
		(3 "B.Mask" user "Board Geometry/Soldermask Bottom")
		(17 "Dwgs.User" user "User.Drawings")
		(19 "Cmts.User" user "User.Comments")
		(21 "Eco1.User" user "User.Eco1")
		(23 "Eco2.User" user "User.Eco2")
		(25 "Edge.Cuts" user "Board Geometry/Outline")
		(27 "Margin" user)
		(31 "F.CrtYd" user "Package Geometry/Place Bound Top")
		(29 "B.CrtYd" user "Package Geometry/Place Bound Bottom")
		(35 "F.Fab" user "Ref Des/Assembly Top")
		(33 "B.Fab" user "Ref Des/Assembly Bottom")
	)
	(footprint ""
		(layer "F.Cu")
		(at 63.246 -37.084 180)
		(property "Reference" "C31"
			(at 0 0 180)
			(layer "F.SilkS")
			(hide yes)
			(effects
				(font
					(size 1.27 1.27)
				)
			)
		)
		(property "Value" "SC1U6D3V2KX-9-GP"
			(at 1.1811 -2.7051 180)
			(unlocked yes)
			(layer "F.Fab")
			(hide yes)
			(effects
				(font
					(size 1.016 1.016)
					(thickness 0.1524)
				)
			)
		)
		(property "Device Type" "C402H22"
			(at 1.1811 -4.2291 180)
			(unlocked yes)
			(layer "F.Fab")
			(hide yes)
			(effects
				(font
					(size 1.016 1.016)
					(thickness 0.1524)
				)
			)
		)
		(duplicate_pad_numbers_are_jumpers no)
		(fp_rect
			(start -0.4318 0.9525)
			(end 0.4318 -0.9525)
			(stroke
				(width 0)
				(type default)
			)
			(fill no)
			(layer "F.CrtYd")
		)
		(fp_rect
			(start -0.4318 0.9525)
			(end 0.4318 -0.9525)
			(stroke
				(width 0)
				(type default)
			)
			(fill no)
			(layer "F.Fab")
		)
		(pad "1" smd custom
			(at 0 -0.4445 180)
			(size 0.1524 0.1524)
			(layers "F.Cu" "F.Mask" "F.Paste")
			(net "P3V3_PWR")
			(options
				(clearance outline)
				(anchor circle)
			)
			(primitives
				(gr_poly
					(pts
						(arc
							(start 0.3048 -0.2032)
							(mid 0.275042 -0.275042)
							(end 0.2032 -0.3048)
						)
						(arc
							(start -0.2032 -0.3048)
							(mid -0.275042 -0.275042)
							(end -0.3048 -0.2032)
						)
						(arc
							(start -0.3048 0.2032)
							(mid -0.275042 0.275042)
							(end -0.2032 0.3048)
						)
						(arc
							(start 0.2032 0.3048)
							(mid 0.275042 0.275042)
							(end 0.3048 0.2032)
						)
					)
					(width 0)
					(fill yes)
				)
			)
		)
		(pad "2" smd custom
			(at 0 0.4445 180)
			(size 0.1524 0.1524)
			(layers "F.Cu" "F.Mask" "F.Paste")
			(net "GND")
			(options
				(clearance outline)
				(anchor circle)
			)
			(primitives
				(gr_poly
					(pts
						(arc
							(start 0.3048 -0.2032)
							(mid 0.275042 -0.275042)
							(end 0.2032 -0.3048)
						)
						(arc
							(start -0.2032 -0.3048)
							(mid -0.275042 -0.275042)
							(end -0.3048 -0.2032)
						)
						(arc
							(start -0.3048 0.2032)
							(mid -0.275042 0.275042)
							(end -0.2032 0.3048)
						)
						(arc
							(start 0.2032 0.3048)
							(mid 0.275042 0.275042)
							(end 0.3048 0.2032)
						)
					)
					(width 0)
					(fill yes)
				)
			)
		)
	)
	(footprint ""
		(layer "F.Cu")
		(at 65.786 -77.216 90)
		(property "Reference" "PC39"
			(at 0 0 90)
			(layer "F.SilkS")
			(hide yes)
			(effects
				(font
					(size 1.27 1.27)
				)
			)
		)
		(property "Value" "SC10U6D3V5KX-4GP"
			(at -0.0762 -6.1214 90)
			(unlocked yes)
			(layer "F.Fab")
			(hide yes)
			(effects
				(font
					(size 1.016 1.016)
					(thickness 0.1524)
				)
			)
		)
		(property "Device Type" "C805H58"
			(at -0.0762 -8.1534 90)
			(unlocked yes)
			(layer "F.Fab")
			(hide yes)
			(effects
				(font
					(size 1.016 1.016)
					(thickness 0.1524)
				)
			)
		)
		(duplicate_pad_numbers_are_jumpers no)
		(fp_line
			(start 0.635 0)
			(end -0.635 0)
			(stroke
				(width 0.508)
				(type default)
			)
			(layer "F.SilkS")
		)
		(fp_rect
			(start -0.9652 1.778)
			(end 0.9652 -1.778)
			(stroke
				(width 0)
				(type default)
			)
			(fill no)
			(layer "F.CrtYd")
		)
		(fp_poly
			(pts
				(xy -0.9652 -1.778) (xy 0.9652 -1.778) (xy 0.9652 1.778) (xy -0.9652 1.778)
			)
			(stroke
				(width 0)
				(type default)
			)
			(fill no)
			(layer "F.Fab")
		)
		(pad "1" smd rect
			(at 0 -0.9652 90)
			(size 1.397 1.143)
			(layers "F.Cu" "F.Mask" "F.Paste")
			(net "P3V3_PWR")
		)
		(pad "2" smd rect
			(at 0 0.9652 90)
			(size 1.397 1.143)
			(layers "F.Cu" "F.Mask" "F.Paste")
			(net "GND")
		)
	)
	(footprint ""
		(layer "F.Cu")
		(at 59.817 -60.579 -90)
		(property "Reference" "C15"
			(at 0 0 270)
			(layer "F.SilkS")
			(hide yes)
			(effects
				(font
					(size 1.27 1.27)
				)
			)
		)
		(property "Value" "SCD1U16V2KX-3GP"
			(at 1.1811 -2.7051 270)
			(unlocked yes)
			(layer "F.Fab")
			(hide yes)
			(effects
				(font
					(size 1.016 1.016)
					(thickness 0.1524)
				)
			)
		)
		(property "Device Type" "C402H22"
			(at 1.1811 -4.2291 270)
			(unlocked yes)
			(layer "F.Fab")
			(hide yes)
			(effects
				(font
					(size 1.016 1.016)
					(thickness 0.1524)
				)
			)
		)
		(duplicate_pad_numbers_are_jumpers no)
		(fp_rect
			(start -0.4318 0.9525)
			(end 0.4318 -0.9525)
			(stroke
				(width 0)
				(type default)
			)
			(fill no)
			(layer "F.CrtYd")
		)
		(fp_rect
			(start -0.4318 0.9525)
			(end 0.4318 -0.9525)
			(stroke
				(width 0)
				(type default)
			)
			(fill no)
			(layer "F.Fab")
		)
		(pad "1" smd custom
			(at 0 -0.4445 270)
			(size 0.1524 0.1524)
			(layers "F.Cu" "F.Mask" "F.Paste")
			(net "P3V3_PWR")
			(options
				(clearance outline)
				(anchor circle)
			)
			(primitives
				(gr_poly
					(pts
						(arc
							(start 0.3048 -0.2032)
							(mid 0.275042 -0.275042)
							(end 0.2032 -0.3048)
						)
						(arc
							(start -0.2032 -0.3048)
							(mid -0.275042 -0.275042)
							(end -0.3048 -0.2032)
						)
						(arc
							(start -0.3048 0.2032)
							(mid -0.275042 0.275042)
							(end -0.2032 0.3048)
						)
						(arc
							(start 0.2032 0.3048)
							(mid 0.275042 0.275042)
							(end 0.3048 0.2032)
						)
					)
					(width 0)
					(fill yes)
				)
			)
		)
		(pad "2" smd custom
			(at 0 0.4445 270)
			(size 0.1524 0.1524)
			(layers "F.Cu" "F.Mask" "F.Paste")
			(net "GND")
			(options
				(clearance outline)
				(anchor circle)
			)
			(primitives
				(gr_poly
					(pts
						(arc
							(start 0.3048 -0.2032)
							(mid 0.275042 -0.275042)
							(end 0.2032 -0.3048)
						)
						(arc
							(start -0.2032 -0.3048)
							(mid -0.275042 -0.275042)
							(end -0.3048 -0.2032)
						)
						(arc
							(start -0.3048 0.2032)
							(mid -0.275042 0.275042)
							(end -0.2032 0.3048)
						)
						(arc
							(start 0.2032 0.3048)
							(mid 0.275042 0.275042)
							(end 0.3048 0.2032)
						)
					)
					(width 0)
					(fill yes)
				)
			)
		)
	)
	(footprint ""
		(layer "F.Cu")
		(at 49.227994 -76.073 -90)
		(property "Reference" "PR37"
			(at 0 0 270)
			(layer "F.SilkS")
			(hide yes)
			(effects
				(font
					(size 1.27 1.27)
				)
			)
		)
		(property "Value" "10KR2F-2-GP"
			(at 0.064008 -3.993896 270)
			(unlocked yes)
			(layer "F.Fab")
			(hide yes)
			(effects
				(font
					(size 1.016 1.016)
					(thickness 0.1524)
				)
			)
		)
		(property "Device Type" "R402H16"
			(at 0.064008 -5.517896 270)
			(unlocked yes)
			(layer "F.Fab")
			(hide yes)
			(effects
				(font
					(size 1.016 1.016)
					(thickness 0.1524)
				)
			)
		)
		(duplicate_pad_numbers_are_jumpers no)
		(fp_line
			(start -0.508 -0.9398)
			(end -0.508 0.9398)
			(stroke
				(width 0.1524)
				(type default)
			)
			(layer "F.SilkS")
		)
		(fp_line
			(start 0.508 -0.9398)
			(end -0.508 -0.9398)
			(stroke
				(width 0.1524)
				(type default)
			)
			(layer "F.SilkS")
		)
		(fp_rect
			(start -0.508 0.9398)
			(end 0.508 -0.9398)
			(stroke
				(width 0)
				(type default)
			)
			(fill no)
			(layer "F.CrtYd")
		)
		(fp_rect
			(start -0.508 0.9398)
			(end 0.508 -0.9398)
			(stroke
				(width 0)
				(type default)
			)
			(fill no)
			(layer "F.Fab")
		)
		(pad "1" smd custom
			(at 0 -0.4445 270)
			(size 0.1397 0.1397)
			(layers "F.Cu" "F.Mask" "F.Paste")
			(net "P3V3_DEV_VFB")
			(options
				(clearance outline)
				(anchor circle)
			)
			(primitives
				(gr_poly
					(pts
						(arc
							(start -0.1778 -0.2794)
							(mid -0.249642 -0.249642)
							(end -0.2794 -0.1778)
						)
						(arc
							(start -0.2794 0.1778)
							(mid -0.249642 0.249642)
							(end -0.1778 0.2794)
						)
						(arc
							(start 0.1778 0.2794)
							(mid 0.249642 0.249642)
							(end 0.2794 0.1778)
						)
						(arc
							(start 0.2794 -0.1778)
							(mid 0.249642 -0.249642)
							(end 0.1778 -0.2794)
						)
					)
					(width 0)
					(fill yes)
				)
			)
		)
		(pad "2" smd custom
			(at 0 0.4445 270)
			(size 0.1397 0.1397)
			(layers "F.Cu" "F.Mask" "F.Paste")
			(net "AGND_P3V3_DEV")
			(options
				(clearance outline)
				(anchor circle)
			)
			(primitives
				(gr_poly
					(pts
						(arc
							(start -0.1778 -0.2794)
							(mid -0.249642 -0.249642)
							(end -0.2794 -0.1778)
						)
						(arc
							(start -0.2794 0.1778)
							(mid -0.249642 0.249642)
							(end -0.1778 0.2794)
						)
						(arc
							(start 0.1778 0.2794)
							(mid 0.249642 0.249642)
							(end 0.2794 0.1778)
						)
						(arc
							(start 0.2794 -0.1778)
							(mid 0.249642 -0.249642)
							(end 0.1778 -0.2794)
						)
					)
					(width 0)
					(fill yes)
				)
			)
		)
	)
	(footprint ""
		(layer "F.Cu")
		(at 75.311 -62.23 -90)
		(property "Reference" "R46"
			(at 0 0 270)
			(layer "F.SilkS")
			(hide yes)
			(effects
				(font
					(size 1.27 1.27)
				)
			)
		)
		(property "Value" "47KR2F-GP"
			(at 0.064008 -3.993896 270)
			(unlocked yes)
			(layer "F.Fab")
			(hide yes)
			(effects
				(font
					(size 1.016 1.016)
					(thickness 0.1524)
				)
			)
		)
		(property "Device Type" "R402H16"
			(at 0.064008 -5.517896 270)
			(unlocked yes)
			(layer "F.Fab")
			(hide yes)
			(effects
				(font
					(size 1.016 1.016)
					(thickness 0.1524)
				)
			)
		)
		(duplicate_pad_numbers_are_jumpers no)
		(fp_line
			(start -0.508 -0.9398)
			(end -0.508 0.9398)
			(stroke
				(width 0.1524)
				(type default)
			)
			(layer "F.SilkS")
		)
		(fp_line
			(start 0.508 -0.9398)
			(end -0.508 -0.9398)
			(stroke
				(width 0.1524)
				(type default)
			)
			(layer "F.SilkS")
		)
		(fp_rect
			(start -0.508 0.9398)
			(end 0.508 -0.9398)
			(stroke
				(width 0)
				(type default)
			)
			(fill no)
			(layer "F.CrtYd")
		)
		(fp_rect
			(start -0.508 0.9398)
			(end 0.508 -0.9398)
			(stroke
				(width 0)
				(type default)
			)
			(fill no)
			(layer "F.Fab")
		)
		(pad "1" smd custom
			(at 0 -0.4445 270)
			(size 0.1397 0.1397)
			(layers "F.Cu" "F.Mask" "F.Paste")
			(net "Z50_SSD_A_PRSNT#")
			(options
				(clearance outline)
				(anchor circle)
			)
			(primitives
				(gr_poly
					(pts
						(arc
							(start -0.1778 -0.2794)
							(mid -0.249642 -0.249642)
							(end -0.2794 -0.1778)
						)
						(arc
							(start -0.2794 0.1778)
							(mid -0.249642 0.249642)
							(end -0.1778 0.2794)
						)
						(arc
							(start 0.1778 0.2794)
							(mid 0.249642 0.249642)
							(end 0.2794 0.1778)
						)
						(arc
							(start 0.2794 -0.1778)
							(mid 0.249642 -0.249642)
							(end 0.1778 -0.2794)
						)
					)
					(width 0)
					(fill yes)
				)
			)
		)
		(pad "2" smd custom
			(at 0 0.4445 270)
			(size 0.1397 0.1397)
			(layers "F.Cu" "F.Mask" "F.Paste")
			(net "GND")
			(options
				(clearance outline)
				(anchor circle)
			)
			(primitives
				(gr_poly
					(pts
						(arc
							(start -0.1778 -0.2794)
							(mid -0.249642 -0.249642)
							(end -0.2794 -0.1778)
						)
						(arc
							(start -0.2794 0.1778)
							(mid -0.249642 0.249642)
							(end -0.1778 0.2794)
						)
						(arc
							(start 0.1778 0.2794)
							(mid 0.249642 0.249642)
							(end 0.2794 0.1778)
						)
						(arc
							(start 0.2794 -0.1778)
							(mid 0.249642 -0.249642)
							(end 0.1778 -0.2794)
						)
					)
					(width 0)
					(fill yes)
				)
			)
		)
	)
	(footprint ""
		(layer "F.Cu")
		(at 52.275994 -77.216 -90)
		(property "Reference" "PR1"
			(at 0 0 270)
			(layer "F.SilkS")
			(hide yes)
			(effects
				(font
					(size 1.27 1.27)
				)
			)
		)
		(property "Value" "37K4R2F-1-GP"
			(at 0.064008 -3.993896 270)
			(unlocked yes)
			(layer "F.Fab")
			(hide yes)
			(effects
				(font
					(size 1.016 1.016)
					(thickness 0.1524)
				)
			)
		)
		(property "Device Type" "R402H16"
			(at 0.064008 -5.517896 270)
			(unlocked yes)
			(layer "F.Fab")
			(hide yes)
			(effects
				(font
					(size 1.016 1.016)
					(thickness 0.1524)
				)
			)
		)
		(duplicate_pad_numbers_are_jumpers no)
		(fp_line
			(start -0.508 -0.9398)
			(end -0.508 0.9398)
			(stroke
				(width 0.1524)
				(type default)
			)
			(layer "F.SilkS")
		)
		(fp_line
			(start 0.508 -0.9398)
			(end -0.508 -0.9398)
			(stroke
				(width 0.1524)
				(type default)
			)
			(layer "F.SilkS")
		)
		(fp_rect
			(start -0.508 0.9398)
			(end 0.508 -0.9398)
			(stroke
				(width 0)
				(type default)
			)
			(fill no)
			(layer "F.CrtYd")
		)
		(fp_rect
			(start -0.508 0.9398)
			(end 0.508 -0.9398)
			(stroke
				(width 0)
				(type default)
			)
			(fill no)
			(layer "F.Fab")
		)
		(pad "1" smd custom
			(at 0 -0.4445 270)
			(size 0.1397 0.1397)
			(layers "F.Cu" "F.Mask" "F.Paste")
			(net "P12V")
			(options
				(clearance outline)
				(anchor circle)
			)
			(primitives
				(gr_poly
					(pts
						(arc
							(start -0.1778 -0.2794)
							(mid -0.249642 -0.249642)
							(end -0.2794 -0.1778)
						)
						(arc
							(start -0.2794 0.1778)
							(mid -0.249642 0.249642)
							(end -0.1778 0.2794)
						)
						(arc
							(start 0.1778 0.2794)
							(mid 0.249642 0.249642)
							(end 0.2794 0.1778)
						)
						(arc
							(start 0.2794 -0.1778)
							(mid 0.249642 -0.249642)
							(end 0.1778 -0.2794)
						)
					)
					(width 0)
					(fill yes)
				)
			)
		)
		(pad "2" smd custom
			(at 0 0.4445 270)
			(size 0.1397 0.1397)
			(layers "F.Cu" "F.Mask" "F.Paste")
			(net "P3V3_DEV_EN")
			(options
				(clearance outline)
				(anchor circle)
			)
			(primitives
				(gr_poly
					(pts
						(arc
							(start -0.1778 -0.2794)
							(mid -0.249642 -0.249642)
							(end -0.2794 -0.1778)
						)
						(arc
							(start -0.2794 0.1778)
							(mid -0.249642 0.249642)
							(end -0.1778 0.2794)
						)
						(arc
							(start 0.1778 0.2794)
							(mid 0.249642 0.249642)
							(end 0.2794 0.1778)
						)
						(arc
							(start 0.2794 -0.1778)
							(mid 0.249642 -0.249642)
							(end 0.1778 -0.2794)
						)
					)
					(width 0)
					(fill yes)
				)
			)
		)
	)
	(footprint ""
		(layer "F.Cu")
		(at 25.019 -82.55 -90)
		(property "Reference" "R32"
			(at 0 0 270)
			(layer "F.SilkS")
			(hide yes)
			(effects
				(font
					(size 1.27 1.27)
				)
			)
		)
		(property "Value" "4K7R2F-GP"
			(at 0.064008 -3.993896 270)
			(unlocked yes)
			(layer "F.Fab")
			(hide yes)
			(effects
				(font
					(size 1.016 1.016)
					(thickness 0.1524)
				)
			)
		)
		(property "Device Type" "R402H16"
			(at 0.064008 -5.517896 270)
			(unlocked yes)
			(layer "F.Fab")
			(hide yes)
			(effects
				(font
					(size 1.016 1.016)
					(thickness 0.1524)
				)
			)
		)
		(duplicate_pad_numbers_are_jumpers no)
		(fp_line
			(start -0.508 -0.9398)
			(end -0.508 0.9398)
			(stroke
				(width 0.1524)
				(type default)
			)
			(layer "F.SilkS")
		)
		(fp_line
			(start 0.508 -0.9398)
			(end -0.508 -0.9398)
			(stroke
				(width 0.1524)
				(type default)
			)
			(layer "F.SilkS")
		)
		(fp_rect
			(start -0.508 0.9398)
			(end 0.508 -0.9398)
			(stroke
				(width 0)
				(type default)
			)
			(fill no)
			(layer "F.CrtYd")
		)
		(fp_rect
			(start -0.508 0.9398)
			(end 0.508 -0.9398)
			(stroke
				(width 0)
				(type default)
			)
			(fill no)
			(layer "F.Fab")
		)
		(pad "1" smd custom
			(at 0 -0.4445 270)
			(size 0.1397 0.1397)
			(layers "F.Cu" "F.Mask" "F.Paste")
			(net "Z50_SMB_SWITCH_RESET#")
			(options
				(clearance outline)
				(anchor circle)
			)
			(primitives
				(gr_poly
					(pts
						(arc
							(start -0.1778 -0.2794)
							(mid -0.249642 -0.249642)
							(end -0.2794 -0.1778)
						)
						(arc
							(start -0.2794 0.1778)
							(mid -0.249642 0.249642)
							(end -0.1778 0.2794)
						)
						(arc
							(start 0.1778 0.2794)
							(mid 0.249642 0.249642)
							(end 0.2794 0.1778)
						)
						(arc
							(start 0.2794 -0.1778)
							(mid 0.249642 -0.249642)
							(end 0.1778 -0.2794)
						)
					)
					(width 0)
					(fill yes)
				)
			)
		)
		(pad "2" smd custom
			(at 0 0.4445 270)
			(size 0.1397 0.1397)
			(layers "F.Cu" "F.Mask" "F.Paste")
			(net "P3V3_DPB")
			(options
				(clearance outline)
				(anchor circle)
			)
			(primitives
				(gr_poly
					(pts
						(arc
							(start -0.1778 -0.2794)
							(mid -0.249642 -0.249642)
							(end -0.2794 -0.1778)
						)
						(arc
							(start -0.2794 0.1778)
							(mid -0.249642 0.249642)
							(end -0.1778 0.2794)
						)
						(arc
							(start 0.1778 0.2794)
							(mid 0.249642 0.249642)
							(end 0.2794 0.1778)
						)
						(arc
							(start 0.2794 -0.1778)
							(mid 0.249642 -0.249642)
							(end 0.1778 -0.2794)
						)
					)
					(width 0)
					(fill yes)
				)
			)
		)
	)
	(footprint ""
		(layer "F.Cu")
		(at 75.184 -34.036)
		(property "Reference" "R47"
			(at 0 0 0)
			(layer "F.SilkS")
			(hide yes)
			(effects
				(font
					(size 1.27 1.27)
				)
			)
		)
		(property "Value" "47KR2F-GP"
			(at 0.064008 -3.993896 0)
			(unlocked yes)
			(layer "F.Fab")
			(hide yes)
			(effects
				(font
					(size 1.016 1.016)
					(thickness 0.1524)
				)
			)
		)
		(property "Device Type" "R402H16"
			(at 0.064008 -5.517896 0)
			(unlocked yes)
			(layer "F.Fab")
			(hide yes)
			(effects
				(font
					(size 1.016 1.016)
					(thickness 0.1524)
				)
			)
		)
		(duplicate_pad_numbers_are_jumpers no)
		(fp_line
			(start -0.508 -0.9398)
			(end -0.508 0.9398)
			(stroke
				(width 0.1524)
				(type default)
			)
			(layer "F.SilkS")
		)
		(fp_line
			(start 0.508 -0.9398)
			(end -0.508 -0.9398)
			(stroke
				(width 0.1524)
				(type default)
			)
			(layer "F.SilkS")
		)
		(fp_rect
			(start -0.508 0.9398)
			(end 0.508 -0.9398)
			(stroke
				(width 0)
				(type default)
			)
			(fill no)
			(layer "F.CrtYd")
		)
		(fp_rect
			(start -0.508 0.9398)
			(end 0.508 -0.9398)
			(stroke
				(width 0)
				(type default)
			)
			(fill no)
			(layer "F.Fab")
		)
		(pad "1" smd custom
			(at 0 -0.4445)
			(size 0.1397 0.1397)
			(layers "F.Cu" "F.Mask" "F.Paste")
			(net "Z50_SSD_B_PRSNT#")
			(options
				(clearance outline)
				(anchor circle)
			)
			(primitives
				(gr_poly
					(pts
						(arc
							(start -0.1778 -0.2794)
							(mid -0.249642 -0.249642)
							(end -0.2794 -0.1778)
						)
						(arc
							(start -0.2794 0.1778)
							(mid -0.249642 0.249642)
							(end -0.1778 0.2794)
						)
						(arc
							(start 0.1778 0.2794)
							(mid 0.249642 0.249642)
							(end 0.2794 0.1778)
						)
						(arc
							(start 0.2794 -0.1778)
							(mid 0.249642 -0.249642)
							(end 0.1778 -0.2794)
						)
					)
					(width 0)
					(fill yes)
				)
			)
		)
		(pad "2" smd custom
			(at 0 0.4445)
			(size 0.1397 0.1397)
			(layers "F.Cu" "F.Mask" "F.Paste")
			(net "GND")
			(options
				(clearance outline)
				(anchor circle)
			)
			(primitives
				(gr_poly
					(pts
						(arc
							(start -0.1778 -0.2794)
							(mid -0.249642 -0.249642)
							(end -0.2794 -0.1778)
						)
						(arc
							(start -0.2794 0.1778)
							(mid -0.249642 0.249642)
							(end -0.1778 0.2794)
						)
						(arc
							(start 0.1778 0.2794)
							(mid 0.249642 0.249642)
							(end 0.2794 0.1778)
						)
						(arc
							(start 0.2794 -0.1778)
							(mid 0.249642 -0.249642)
							(end 0.1778 -0.2794)
						)
					)
					(width 0)
					(fill yes)
				)
			)
		)
	)
)
